(kicad_pcb
	(version 20260206)
	(generator "pcbnew")
	(generator_version "10.0")
	(general
		(thickness 1.6)
		(legacy_teardrops no)
	)
	(paper "A4")
	(title_block
		(title "04192023_DAF0TMB3IC0_F0TG_MB_C_brd_V02_OCP.brd")
		(comment 1 "Grand Teton / footprints 4181-4187 of 8354")
	)
	(layers
		(0 "F.Cu" signal "TOP")
		(4 "In1.Cu" signal "GND")
		(6 "In2.Cu" signal "IN1")
		(8 "In3.Cu" signal "GND1")
		(10 "In4.Cu" signal "IN2")
		(12 "In5.Cu" signal "GND2")
		(14 "In6.Cu" signal "IN3")
		(16 "In7.Cu" signal "GND3")
		(18 "In8.Cu" signal "VCC")
		(20 "In9.Cu" signal "VCC1")
		(22 "In10.Cu" signal "GND4")
		(24 "In11.Cu" signal "IN4")
		(26 "In12.Cu" signal "GND5")
		(28 "In13.Cu" signal "IN5")
		(30 "In14.Cu" signal "GND6")
		(32 "In15.Cu" signal "IN6")
		(34 "In16.Cu" signal "GND7")
		(2 "B.Cu" signal "BOTTOM")
		(9 "F.Adhes" user "F.Adhesive")
		(11 "B.Adhes" user "B.Adhesive")
		(13 "F.Paste" user "Package Geometry/Pastemask Top")
		(15 "B.Paste" user "Package Geometry/Pastemask Bottom")
		(5 "F.SilkS" user "Ref Des/Silkscreen Top")
		(7 "B.SilkS" user "Ref Des/Silkscreen Bottom")
		(1 "F.Mask" user "Board Geometry/Soldermask Top")
		(3 "B.Mask" user "Board Geometry/Soldermask Bottom")
		(17 "Dwgs.User" user "User.Drawings")
		(19 "Cmts.User" user "User.Comments")
		(21 "Eco1.User" user "User.Eco1")
		(23 "Eco2.User" user "User.Eco2")
		(25 "Edge.Cuts" user "Board Geometry/Outline")
		(27 "Margin" user)
		(31 "F.CrtYd" user "Package Geometry/Place Bound Top")
		(29 "B.CrtYd" user "Package Geometry/Place Bound Bottom")
		(35 "F.Fab" user "Ref Des/Assembly Top")
		(33 "B.Fab" user "Ref Des/Assembly Bottom")
	)
	(footprint ""
		(layer "F.Cu")
		(at 281.621738 -390.49452 -90)
		(property "Reference" "R2627"
			(at 0 0 270)
			(layer "F.SilkS")
			(hide yes)
			(effects
				(font
					(size 1.27 1.27)
				)
			)
		)
		(property "Value" ""
			(at 0 0 270)
			(layer "F.Fab")
			(effects
				(font
					(size 1.27 1.27)
				)
			)
		)
		(duplicate_pad_numbers_are_jumpers no)
		(fp_line
			(start -0.7874 0.4064)
			(end -0.7874 -0.4064)
			(stroke
				(width 0.1524)
				(type default)
			)
			(layer "F.SilkS")
		)
		(fp_line
			(start 0.7874 0.4064)
			(end -0.7874 0.4064)
			(stroke
				(width 0.1524)
				(type default)
			)
			(layer "F.SilkS")
		)
		(fp_line
			(start -0.7874 -0.4064)
			(end 0.7874 -0.4064)
			(stroke
				(width 0.1524)
				(type default)
			)
			(layer "F.SilkS")
		)
		(fp_line
			(start 0.7874 -0.4064)
			(end 0.7874 0.4064)
			(stroke
				(width 0.1524)
				(type default)
			)
			(layer "F.SilkS")
		)
		(fp_line
			(start -0.67945 0.3048)
			(end -0.67945 -0.305054)
			(stroke
				(width 0.1)
				(type default)
			)
			(layer "F.Fab")
		)
		(fp_line
			(start -0.12065 0.3048)
			(end -0.67945 0.3048)
			(stroke
				(width 0.1)
				(type default)
			)
			(layer "F.Fab")
		)
		(fp_line
			(start 0.120396 0.3048)
			(end 0.120396 0.2794)
			(stroke
				(width 0.1)
				(type default)
			)
			(layer "F.Fab")
		)
		(fp_line
			(start 0.67945 0.3048)
			(end 0.120396 0.3048)
			(stroke
				(width 0.1)
				(type default)
			)
			(layer "F.Fab")
		)
		(fp_line
			(start -0.12065 0.2794)
			(end -0.12065 0.3048)
			(stroke
				(width 0.1)
				(type default)
			)
			(layer "F.Fab")
		)
		(fp_line
			(start 0.120396 0.2794)
			(end -0.12065 0.2794)
			(stroke
				(width 0.1)
				(type default)
			)
			(layer "F.Fab")
		)
		(fp_line
			(start -0.12065 -0.2794)
			(end 0.12065 -0.2794)
			(stroke
				(width 0.1)
				(type default)
			)
			(layer "F.Fab")
		)
		(fp_line
			(start 0.12065 -0.2794)
			(end 0.12065 -0.3048)
			(stroke
				(width 0.1)
				(type default)
			)
			(layer "F.Fab")
		)
		(fp_line
			(start 0.12065 -0.3048)
			(end 0.67945 -0.3048)
			(stroke
				(width 0.1)
				(type default)
			)
			(layer "F.Fab")
		)
		(fp_line
			(start 0.67945 -0.3048)
			(end 0.67945 0.3048)
			(stroke
				(width 0.1)
				(type default)
			)
			(layer "F.Fab")
		)
		(fp_line
			(start -0.67945 -0.305054)
			(end -0.12065 -0.305054)
			(stroke
				(width 0.1)
				(type default)
			)
			(layer "F.Fab")
		)
		(fp_line
			(start -0.12065 -0.305054)
			(end -0.12065 -0.2794)
			(stroke
				(width 0.1)
				(type default)
			)
			(layer "F.Fab")
		)
		(pad "1" smd circle
			(at -0.40005 0 270)
			(size 0 0)
			(layers "F.Cu" "F.Mask" "F.Paste")
			(net "SMB_P12V_HSC_TEMP_SDA")
		)
		(pad "2" smd circle
			(at 0.40005 0 270)
			(size 0 0)
			(layers "F.Cu" "F.Mask" "F.Paste")
			(net "SMB_P12V_HSC_SDA")
		)
	)
	(footprint ""
		(layer "F.Cu")
		(at 404.63724 -383.88163 -90)
		(property "Reference" "C860"
			(at 0 0 270)
			(layer "F.SilkS")
			(hide yes)
			(effects
				(font
					(size 1.27 1.27)
				)
			)
		)
		(property "Value" ""
			(at 0 0 270)
			(layer "F.Fab")
			(effects
				(font
					(size 1.27 1.27)
				)
			)
		)
		(duplicate_pad_numbers_are_jumpers no)
		(fp_line
			(start -0.299974 0.150114)
			(end -0.299974 -0.150114)
			(stroke
				(width 0.1)
				(type default)
			)
			(layer "F.Fab")
		)
		(fp_line
			(start 0.299974 0.150114)
			(end -0.299974 0.150114)
			(stroke
				(width 0.1)
				(type default)
			)
			(layer "F.Fab")
		)
		(fp_line
			(start -0.299974 -0.150114)
			(end 0.299974 -0.150114)
			(stroke
				(width 0.1)
				(type default)
			)
			(layer "F.Fab")
		)
		(fp_line
			(start 0.299974 -0.150114)
			(end 0.299974 0.150114)
			(stroke
				(width 0.1)
				(type default)
			)
			(layer "F.Fab")
		)
		(pad "1" smd rect
			(at -0.2667 0 270)
			(size 0.3048 0.381)
			(layers "F.Cu" "F.Mask" "F.Paste")
			(net "P5E_CPU0_P2_TX_C_DN<4>")
		)
		(pad "2" smd rect
			(at 0.2667 0 270)
			(size 0.3048 0.381)
			(layers "F.Cu" "F.Mask" "F.Paste")
			(net "P5E_CPU0_P2_TX_DN<4>")
		)
	)
	(footprint ""
		(layer "F.Cu")
		(at 158.848044 -370.57203 -90)
		(property "Reference" "C754"
			(at 0 0 270)
			(layer "F.SilkS")
			(hide yes)
			(effects
				(font
					(size 1.27 1.27)
				)
			)
		)
		(property "Value" ""
			(at 0 0 270)
			(layer "F.Fab")
			(effects
				(font
					(size 1.27 1.27)
				)
			)
		)
		(duplicate_pad_numbers_are_jumpers no)
		(fp_line
			(start -0.299974 0.150114)
			(end -0.299974 -0.150114)
			(stroke
				(width 0.1)
				(type default)
			)
			(layer "F.Fab")
		)
		(fp_line
			(start 0.299974 0.150114)
			(end -0.299974 0.150114)
			(stroke
				(width 0.1)
				(type default)
			)
			(layer "F.Fab")
		)
		(fp_line
			(start -0.299974 -0.150114)
			(end 0.299974 -0.150114)
			(stroke
				(width 0.1)
				(type default)
			)
			(layer "F.Fab")
		)
		(fp_line
			(start 0.299974 -0.150114)
			(end 0.299974 0.150114)
			(stroke
				(width 0.1)
				(type default)
			)
			(layer "F.Fab")
		)
		(pad "1" smd rect
			(at -0.2667 0 270)
			(size 0.3048 0.381)
			(layers "F.Cu" "F.Mask" "F.Paste")
			(net "P5E_CPU1_P2_TX_C_DN<9>")
		)
		(pad "2" smd rect
			(at 0.2667 0 270)
			(size 0.3048 0.381)
			(layers "F.Cu" "F.Mask" "F.Paste")
			(net "P5E_CPU1_P2_TX_DN<9>")
		)
	)
	(footprint ""
		(layer "F.Cu")
		(at 371.915944 -178.0921 -90)
		(property "Reference" "PR323"
			(at 0 0 270)
			(layer "F.SilkS")
			(hide yes)
			(effects
				(font
					(size 1.27 1.27)
				)
			)
		)
		(property "Value" ""
			(at 0 0 270)
			(layer "F.Fab")
			(effects
				(font
					(size 1.27 1.27)
				)
			)
		)
		(duplicate_pad_numbers_are_jumpers no)
		(fp_line
			(start -0.7874 0.4064)
			(end -0.7874 -0.4064)
			(stroke
				(width 0.1524)
				(type default)
			)
			(layer "F.SilkS")
		)
		(fp_line
			(start 0.7874 0.4064)
			(end -0.7874 0.4064)
			(stroke
				(width 0.1524)
				(type default)
			)
			(layer "F.SilkS")
		)
		(fp_line
			(start -0.7874 -0.4064)
			(end 0.7874 -0.4064)
			(stroke
				(width 0.1524)
				(type default)
			)
			(layer "F.SilkS")
		)
		(fp_line
			(start 0.7874 -0.4064)
			(end 0.7874 0.4064)
			(stroke
				(width 0.1524)
				(type default)
			)
			(layer "F.SilkS")
		)
		(fp_line
			(start -0.67945 0.3048)
			(end -0.67945 -0.305054)
			(stroke
				(width 0.1)
				(type default)
			)
			(layer "F.Fab")
		)
		(fp_line
			(start -0.12065 0.3048)
			(end -0.67945 0.3048)
			(stroke
				(width 0.1)
				(type default)
			)
			(layer "F.Fab")
		)
		(fp_line
			(start 0.120396 0.3048)
			(end 0.120396 0.2794)
			(stroke
				(width 0.1)
				(type default)
			)
			(layer "F.Fab")
		)
		(fp_line
			(start 0.67945 0.3048)
			(end 0.120396 0.3048)
			(stroke
				(width 0.1)
				(type default)
			)
			(layer "F.Fab")
		)
		(fp_line
			(start -0.12065 0.2794)
			(end -0.12065 0.3048)
			(stroke
				(width 0.1)
				(type default)
			)
			(layer "F.Fab")
		)
		(fp_line
			(start 0.120396 0.2794)
			(end -0.12065 0.2794)
			(stroke
				(width 0.1)
				(type default)
			)
			(layer "F.Fab")
		)
		(fp_line
			(start -0.12065 -0.2794)
			(end 0.12065 -0.2794)
			(stroke
				(width 0.1)
				(type default)
			)
			(layer "F.Fab")
		)
		(fp_line
			(start 0.12065 -0.2794)
			(end 0.12065 -0.3048)
			(stroke
				(width 0.1)
				(type default)
			)
			(layer "F.Fab")
		)
		(fp_line
			(start 0.12065 -0.3048)
			(end 0.67945 -0.3048)
			(stroke
				(width 0.1)
				(type default)
			)
			(layer "F.Fab")
		)
		(fp_line
			(start 0.67945 -0.3048)
			(end 0.67945 0.3048)
			(stroke
				(width 0.1)
				(type default)
			)
			(layer "F.Fab")
		)
		(fp_line
			(start -0.67945 -0.305054)
			(end -0.12065 -0.305054)
			(stroke
				(width 0.1)
				(type default)
			)
			(layer "F.Fab")
		)
		(fp_line
			(start -0.12065 -0.305054)
			(end -0.12065 -0.2794)
			(stroke
				(width 0.1)
				(type default)
			)
			(layer "F.Fab")
		)
		(pad "1" smd circle
			(at -0.40005 0 270)
			(size 0 0)
			(layers "F.Cu" "F.Mask" "F.Paste")
			(net "SW_PVDDCR_CPU0_P0_BOOT2")
		)
		(pad "2" smd circle
			(at 0.40005 0 270)
			(size 0 0)
			(layers "F.Cu" "F.Mask" "F.Paste")
			(net "SW_PVDDCR_CPU0_P0_BOOT2_RC")
		)
	)
	(footprint ""
		(layer "F.Cu")
		(at 409.792424 -139.362942 89.946)
		(property "Reference" "PR8091"
			(at 0 0 89.946)
			(layer "F.SilkS")
			(hide yes)
			(effects
				(font
					(size 1.27 1.27)
				)
			)
		)
		(property "Value" ""
			(at 0 0 89.946)
			(layer "F.Fab")
			(effects
				(font
					(size 1.27 1.27)
				)
			)
		)
		(duplicate_pad_numbers_are_jumpers no)
		(fp_line
			(start -0.787275 -0.40642)
			(end 0.787525 -0.40638)
			(stroke
				(width 0.1524)
				(type default)
			)
			(layer "F.SilkS")
		)
		(fp_line
			(start 0.787525 -0.40638)
			(end 0.787275 0.40642)
			(stroke
				(width 0.1524)
				(type default)
			)
			(layer "F.SilkS")
		)
		(fp_line
			(start -0.787525 0.40638)
			(end -0.787275 -0.40642)
			(stroke
				(width 0.1524)
				(type default)
			)
			(layer "F.SilkS")
		)
		(fp_line
			(start 0.787275 0.40642)
			(end -0.787525 0.40638)
			(stroke
				(width 0.1524)
				(type default)
			)
			(layer "F.SilkS")
		)
		(fp_line
			(start -0.679484 -0.305176)
			(end -0.120683 -0.30494)
			(stroke
				(width 0.1)
				(type default)
			)
			(layer "F.Fab")
		)
		(fp_line
			(start -0.120683 -0.30494)
			(end -0.120659 -0.279286)
			(stroke
				(width 0.1)
				(type default)
			)
			(layer "F.Fab")
		)
		(fp_line
			(start 0.120617 -0.304914)
			(end 0.679417 -0.304678)
			(stroke
				(width 0.1)
				(type default)
			)
			(layer "F.Fab")
		)
		(fp_line
			(start 0.679417 -0.304678)
			(end 0.679484 0.304922)
			(stroke
				(width 0.1)
				(type default)
			)
			(layer "F.Fab")
		)
		(fp_line
			(start 0.120641 -0.279514)
			(end 0.120617 -0.304914)
			(stroke
				(width 0.1)
				(type default)
			)
			(layer "F.Fab")
		)
		(fp_line
			(start -0.120659 -0.279286)
			(end 0.120641 -0.279514)
			(stroke
				(width 0.1)
				(type default)
			)
			(layer "F.Fab")
		)
		(fp_line
			(start 0.120405 0.279287)
			(end -0.120641 0.279514)
			(stroke
				(width 0.1)
				(type default)
			)
			(layer "F.Fab")
		)
		(fp_line
			(start -0.120641 0.279514)
			(end -0.120617 0.304914)
			(stroke
				(width 0.1)
				(type default)
			)
			(layer "F.Fab")
		)
		(fp_line
			(start -0.679417 0.304678)
			(end -0.679484 -0.305176)
			(stroke
				(width 0.1)
				(type default)
			)
			(layer "F.Fab")
		)
		(fp_line
			(start 0.120429 0.304687)
			(end 0.120405 0.279287)
			(stroke
				(width 0.1)
				(type default)
			)
			(layer "F.Fab")
		)
		(fp_line
			(start -0.120617 0.304914)
			(end -0.679417 0.304678)
			(stroke
				(width 0.1)
				(type default)
			)
			(layer "F.Fab")
		)
		(fp_line
			(start 0.679484 0.304922)
			(end 0.120429 0.304687)
			(stroke
				(width 0.1)
				(type default)
			)
			(layer "F.Fab")
		)
		(pad "1" smd circle
			(at -0.40005 0 89.946)
			(size 0 0)
			(layers "F.Cu" "F.Mask" "F.Paste")
			(net "P5V_AUX_FB")
		)
		(pad "2" smd circle
			(at 0.40005 0 89.946)
			(size 0 0)
			(layers "F.Cu" "F.Mask" "F.Paste")
			(net "GND")
		)
	)
	(footprint ""
		(layer "F.Cu")
		(at 29.299662 -429.759364 90)
		(property "Reference" "R3279"
			(at 0 0 90)
			(layer "F.SilkS")
			(hide yes)
			(effects
				(font
					(size 1.27 1.27)
				)
			)
		)
		(property "Value" ""
			(at 0 0 90)
			(layer "F.Fab")
			(effects
				(font
					(size 1.27 1.27)
				)
			)
		)
		(duplicate_pad_numbers_are_jumpers no)
		(fp_line
			(start 0.7874 -0.4064)
			(end 0.7874 0.4064)
			(stroke
				(width 0.1524)
				(type default)
			)
			(layer "F.SilkS")
		)
		(fp_line
			(start -0.7874 -0.4064)
			(end 0.7874 -0.4064)
			(stroke
				(width 0.1524)
				(type default)
			)
			(layer "F.SilkS")
		)
		(fp_line
			(start 0.7874 0.4064)
			(end -0.7874 0.4064)
			(stroke
				(width 0.1524)
				(type default)
			)
			(layer "F.SilkS")
		)
		(fp_line
			(start -0.7874 0.4064)
			(end -0.7874 -0.4064)
			(stroke
				(width 0.1524)
				(type default)
			)
			(layer "F.SilkS")
		)
		(fp_line
			(start -0.12065 -0.305054)
			(end -0.12065 -0.2794)
			(stroke
				(width 0.1)
				(type default)
			)
			(layer "F.Fab")
		)
		(fp_line
			(start -0.67945 -0.305054)
			(end -0.12065 -0.305054)
			(stroke
				(width 0.1)
				(type default)
			)
			(layer "F.Fab")
		)
		(fp_line
			(start 0.67945 -0.3048)
			(end 0.67945 0.3048)
			(stroke
				(width 0.1)
				(type default)
			)
			(layer "F.Fab")
		)
		(fp_line
			(start 0.12065 -0.3048)
			(end 0.67945 -0.3048)
			(stroke
				(width 0.1)
				(type default)
			)
			(layer "F.Fab")
		)
		(fp_line
			(start 0.12065 -0.2794)
			(end 0.12065 -0.3048)
			(stroke
				(width 0.1)
				(type default)
			)
			(layer "F.Fab")
		)
		(fp_line
			(start -0.12065 -0.2794)
			(end 0.12065 -0.2794)
			(stroke
				(width 0.1)
				(type default)
			)
			(layer "F.Fab")
		)
		(fp_line
			(start 0.120396 0.2794)
			(end -0.12065 0.2794)
			(stroke
				(width 0.1)
				(type default)
			)
			(layer "F.Fab")
		)
		(fp_line
			(start -0.12065 0.2794)
			(end -0.12065 0.3048)
			(stroke
				(width 0.1)
				(type default)
			)
			(layer "F.Fab")
		)
		(fp_line
			(start 0.67945 0.3048)
			(end 0.120396 0.3048)
			(stroke
				(width 0.1)
				(type default)
			)
			(layer "F.Fab")
		)
		(fp_line
			(start 0.120396 0.3048)
			(end 0.120396 0.2794)
			(stroke
				(width 0.1)
				(type default)
			)
			(layer "F.Fab")
		)
		(fp_line
			(start -0.12065 0.3048)
			(end -0.67945 0.3048)
			(stroke
				(width 0.1)
				(type default)
			)
			(layer "F.Fab")
		)
		(fp_line
			(start -0.67945 0.3048)
			(end -0.67945 -0.305054)
			(stroke
				(width 0.1)
				(type default)
			)
			(layer "F.Fab")
		)
		(pad "1" smd circle
			(at -0.40005 0 90)
			(size 0 0)
			(layers "F.Cu" "F.Mask" "F.Paste")
			(net "FM_P2E_EQB1")
		)
		(pad "2" smd circle
			(at 0.40005 0 90)
			(size 0 0)
			(layers "F.Cu" "F.Mask" "F.Paste")
			(net "GND")
		)
	)
	(footprint ""
		(layer "F.Cu")
		(at 419.230302 -436.164736 90)
		(property "Reference" "R4159"
			(at 0 0 90)
			(layer "F.SilkS")
			(hide yes)
			(effects
				(font
					(size 1.27 1.27)
				)
			)
		)
		(property "Value" ""
			(at 0 0 90)
			(layer "F.Fab")
			(effects
				(font
					(size 1.27 1.27)
				)
			)
		)
		(duplicate_pad_numbers_are_jumpers no)
		(fp_line
			(start 0.7874 -0.4064)
			(end 0.7874 0.4064)
			(stroke
				(width 0.1524)
				(type default)
			)
			(layer "F.SilkS")
		)
		(fp_line
			(start -0.7874 -0.4064)
			(end 0.7874 -0.4064)
			(stroke
				(width 0.1524)
				(type default)
			)
			(layer "F.SilkS")
		)
		(fp_line
			(start 0.7874 0.4064)
			(end -0.7874 0.4064)
			(stroke
				(width 0.1524)
				(type default)
			)
			(layer "F.SilkS")
		)
		(fp_line
			(start -0.7874 0.4064)
			(end -0.7874 -0.4064)
			(stroke
				(width 0.1524)
				(type default)
			)
			(layer "F.SilkS")
		)
		(fp_line
			(start -0.12065 -0.305054)
			(end -0.12065 -0.2794)
			(stroke
				(width 0.1)
				(type default)
			)
			(layer "F.Fab")
		)
		(fp_line
			(start -0.67945 -0.305054)
			(end -0.12065 -0.305054)
			(stroke
				(width 0.1)
				(type default)
			)
			(layer "F.Fab")
		)
		(fp_line
			(start 0.67945 -0.3048)
			(end 0.67945 0.3048)
			(stroke
				(width 0.1)
				(type default)
			)
			(layer "F.Fab")
		)
		(fp_line
			(start 0.12065 -0.3048)
			(end 0.67945 -0.3048)
			(stroke
				(width 0.1)
				(type default)
			)
			(layer "F.Fab")
		)
		(fp_line
			(start 0.12065 -0.2794)
			(end 0.12065 -0.3048)
			(stroke
				(width 0.1)
				(type default)
			)
			(layer "F.Fab")
		)
		(fp_line
			(start -0.12065 -0.2794)
			(end 0.12065 -0.2794)
			(stroke
				(width 0.1)
				(type default)
			)
			(layer "F.Fab")
		)
		(fp_line
			(start 0.120396 0.2794)
			(end -0.12065 0.2794)
			(stroke
				(width 0.1)
				(type default)
			)
			(layer "F.Fab")
		)
		(fp_line
			(start -0.12065 0.2794)
			(end -0.12065 0.3048)
			(stroke
				(width 0.1)
				(type default)
			)
			(layer "F.Fab")
		)
		(fp_line
			(start 0.67945 0.3048)
			(end 0.120396 0.3048)
			(stroke
				(width 0.1)
				(type default)
			)
			(layer "F.Fab")
		)
		(fp_line
			(start 0.120396 0.3048)
			(end 0.120396 0.2794)
			(stroke
				(width 0.1)
				(type default)
			)
			(layer "F.Fab")
		)
		(fp_line
			(start -0.12065 0.3048)
			(end -0.67945 0.3048)
			(stroke
				(width 0.1)
				(type default)
			)
			(layer "F.Fab")
		)
		(fp_line
			(start -0.67945 0.3048)
			(end -0.67945 -0.305054)
			(stroke
				(width 0.1)
				(type default)
			)
			(layer "F.Fab")
		)
		(pad "1" smd circle
			(at -0.40005 0 90)
			(size 0 0)
			(layers "F.Cu" "F.Mask" "F.Paste")
			(net "GPU_3V3IO_RSVD1")
		)
		(pad "2" smd circle
			(at 0.40005 0 90)
			(size 0 0)
			(layers "F.Cu" "F.Mask" "F.Paste")
			(net "GND")
		)
	)
)
